%FSTAX23Y23*%
%MOIN*%
%SFA1B1*%

%IPPOS*%
%ADD26R,0.028000X0.165000*%
%ADD27R,0.028000X0.126000*%
%ADD33R,0.057090X0.045280*%
%ADD35R,0.041340X0.043310*%
%ADD37R,0.043310X0.041340*%
%ADD77R,0.045280X0.057090*%
%ADD81R,0.082870X0.044090*%
%ADD184R,0.025200X0.026770*%
%LNtimingcard_pcb-1*%
%LPD*%
G54D26*
X01915Y00137D03*
X02545D03*
X02624D03*
X02899D03*
X03057D03*
X02742D03*
X02938D03*
X02781D03*
X02309D03*
X02427D03*
X02584D03*
X02072D03*
X02033D03*
X01994D03*
X01954D03*
X0219D03*
X02348D03*
X02387D03*
X02466D03*
X02505D03*
X0282D03*
X02663D03*
X0286D03*
X02978D03*
X03017D03*
X02702D03*
X02112D03*
X02151D03*
X01836D03*
X01875D03*
X03096D03*
G54D27*
X01797Y00157D03*
G54D33*
X02632Y03042D03*
Y02971D03*
G54D35*
X02341Y02854D03*
X02396D03*
G54D37*
X02712Y03043D03*
Y02988D03*
G54D77*
X02327Y02944D03*
X02398D03*
G54D81*
X02334Y03279D03*
Y032D03*
Y03121D03*
Y03042D03*
X02509Y03279D03*
Y03121D03*
Y032D03*
Y03042D03*
G54D184*
X02349Y00362D03*
Y00329D03*
X02389D03*
Y00362D03*
X02468D03*
Y00329D03*
X02511D03*
Y00362D03*
X02664Y00329D03*
Y00362D03*
X02704Y00329D03*
Y00362D03*
X02819Y00329D03*
Y00362D03*
X02854D03*
Y00329D03*
X02979D03*
Y00362D03*
X03019Y00329D03*
Y00362D03*
M02*